(kicad_pcb
	(version 20240108)
	(generator "pcbnew")
	(generator_version "8.0")
	(general
		(thickness 1.62)
		(legacy_teardrops no)
	)
	(paper "A4")
	(title_block
		(title "Jetson Orin Baseboard")
		(date "2025-03-12")
		(rev "1.3.4")
		(company "Antmicro Ltd")
		(comment 1 "www.antmicro.com")
		(comment 9 "footprints 632-635 of 677")
	)
	(layers
		(0 "F.Cu" signal)
		(1 "In1.Cu" signal)
		(2 "In2.Cu" signal)
		(3 "In3.Cu" signal)
		(4 "In4.Cu" jumper)
		(5 "In5.Cu" signal)
		(6 "In6.Cu" signal)
		(31 "B.Cu" signal)
		(32 "B.Adhes" user "B.Adhesive")
		(33 "F.Adhes" user "F.Adhesive")
		(34 "B.Paste" user)
		(35 "F.Paste" user)
		(36 "B.SilkS" user "B.Silkscreen")
		(37 "F.SilkS" user "F.Silkscreen")
		(38 "B.Mask" user)
		(39 "F.Mask" user)
		(40 "Dwgs.User" user "User.Drawings")
		(41 "Cmts.User" user "User.Comments")
		(42 "Eco1.User" user "User.Eco1")
		(43 "Eco2.User" user "User.Eco2")
		(44 "Edge.Cuts" user)
		(45 "Margin" user)
		(46 "B.CrtYd" user "B.Courtyard")
		(47 "F.CrtYd" user "F.Courtyard")
		(48 "B.Fab" user)
		(49 "F.Fab" user)
	)
	(footprint "antmicro-footprints:R_0402_1005Metric"
		(layer "B.Cu")
		(at 142 112.4 180)
		(descr "Resistor SMD 0402")
		(tags "resistor SMD 0402")
		(property "Reference" "R197"
			(at -1.25 0.4 0)
			(layer "B.SilkS")
			(effects
				(font
					(size 0.7 0.7)
					(thickness 0.15)
				)
				(justify left bottom mirror)
			)
		)
		(property "Value" "R_470R_0402"
			(at 0 -1.4 0)
			(layer "B.Fab")
			(effects
				(font
					(size 0.7 0.7)
					(thickness 0.15)
				)
				(justify left bottom mirror)
			)
		)
		(property "Footprint" "antmicro-footprints:R_0402_1005Metric"
			(at 0 0 180)
			(layer "F.Fab")
			(hide yes)
			(effects
				(font
					(size 1.27 1.27)
					(thickness 0.15)
				)
			)
		)
		(property "Datasheet" "https://www.bourns.com/docs/product-datasheets/cr.pdf"
			(at 0 0 180)
			(layer "F.Fab")
			(hide yes)
			(effects
				(font
					(size 1.27 1.27)
					(thickness 0.15)
				)
			)
		)
		(property "Author" "Antmicro"
			(at 284 224.8 0)
			(layer "B.Fab")
			(hide yes)
			(effects
				(font
					(size 1 1)
					(thickness 0.15)
				)
				(justify mirror)
			)
		)
		(property "License" "Apache-2.0"
			(at 284 224.8 0)
			(layer "B.Fab")
			(hide yes)
			(effects
				(font
					(size 1 1)
					(thickness 0.15)
				)
				(justify mirror)
			)
		)
		(property "MPN" "CR0402-FX-4700GLF"
			(at 284 224.8 0)
			(layer "B.Fab")
			(hide yes)
			(effects
				(font
					(size 1 1)
					(thickness 0.15)
				)
				(justify mirror)
			)
		)
		(property "Manufacturer" "Bourns"
			(at 284 224.8 0)
			(layer "B.Fab")
			(hide yes)
			(effects
				(font
					(size 1 1)
					(thickness 0.15)
				)
				(justify mirror)
			)
		)
		(property "Tolerance" "1%"
			(at 284 224.8 0)
			(layer "B.Fab")
			(hide yes)
			(effects
				(font
					(size 1 1)
					(thickness 0.15)
				)
				(justify mirror)
			)
		)
		(property "Val" "470R"
			(at 284 224.8 0)
			(layer "B.Fab")
			(hide yes)
			(effects
				(font
					(size 1 1)
					(thickness 0.15)
				)
				(justify mirror)
			)
		)
		(sheetname "CSI")
		(sheetfile "csi.kicad_sch")
		(attr smd)
		(fp_rect
			(start -0.925 0.47)
			(end 0.925 -0.47)
			(stroke
				(width 0.05)
				(type default)
			)
			(fill none)
			(layer "B.CrtYd")
		)
		(fp_rect
			(start -0.5 0.25)
			(end 0.5 -0.25)
			(stroke
				(width 0.15)
				(type solid)
			)
			(fill none)
			(layer "B.Fab")
		)
		(fp_text user "Author: Antmicro"
			(at -0.95 -4.169 0)
			(layer "B.Fab")
			(hide yes)
			(effects
				(font
					(size 0.7 0.7)
					(thickness 0.15)
				)
				(justify left bottom mirror)
			)
		)
		(fp_text user "License: Apache-2.0"
			(at -0.95 -5.169 0)
			(layer "B.Fab")
			(hide yes)
			(effects
				(font
					(size 0.7 0.7)
					(thickness 0.15)
				)
				(justify left bottom mirror)
			)
		)
		(fp_text user "${REFERENCE}"
			(at -0.95 -3.168 0)
			(layer "B.Fab")
			(hide yes)
			(effects
				(font
					(size 0.7 0.7)
					(thickness 0.15)
				)
				(justify left bottom mirror)
			)
		)
		(pad "1" smd roundrect
			(at -0.48 0 180)
			(size 0.59 0.64)
			(layers "B.Cu" "B.Paste" "B.Mask")
			(roundrect_rratio 0.25)
			(net 160 "Net-(D20-A)")
			(pintype "passive")
		)
		(pad "2" smd roundrect
			(at 0.48 0 180)
			(size 0.59 0.64)
			(layers "B.Cu" "B.Paste" "B.Mask")
			(roundrect_rratio 0.25)
			(net 109 "/CSI/CSIA_5V")
			(pintype "passive")
		)
	)
	(footprint "antmicro-footprints:C_0402_1005Metric"
		(layer "B.Cu")
		(at 47.8 112.68 180)
		(descr "Capacitor SMD 0402")
		(tags "capacitor SMD 0402")
		(property "Reference" "C159"
			(at 0.9 -0.22 0)
			(layer "B.SilkS")
			(effects
				(font
					(size 0.7 0.7)
					(thickness 0.15)
				)
				(justify left bottom mirror)
			)
		)
		(property "Value" "C_100n_0402"
			(at -1.022927 -2.155213 0)
			(layer "B.Fab")
			(effects
				(font
					(size 0.7 0.7)
					(thickness 0.15)
				)
				(justify left bottom mirror)
			)
		)
		(property "Footprint" "antmicro-footprints:C_0402_1005Metric"
			(at 0 0 180)
			(layer "F.Fab")
			(hide yes)
			(effects
				(font
					(size 1.27 1.27)
					(thickness 0.15)
				)
			)
		)
		(property "Datasheet" "https://www.murata.com/products/productdetail?partno=GRM155R61H104KE14%23"
			(at 0 0 180)
			(layer "F.Fab")
			(hide yes)
			(effects
				(font
					(size 1.27 1.27)
					(thickness 0.15)
				)
			)
		)
		(property "Author" "Antmicro"
			(at 95.6 225.36 0)
			(layer "B.Fab")
			(hide yes)
			(effects
				(font
					(size 1 1)
					(thickness 0.15)
				)
				(justify mirror)
			)
		)
		(property "Dielectric" "X5R"
			(at 95.6 225.36 0)
			(layer "B.Fab")
			(hide yes)
			(effects
				(font
					(size 1 1)
					(thickness 0.15)
				)
				(justify mirror)
			)
		)
		(property "License" "Apache-2.0"
			(at 95.6 225.36 0)
			(layer "B.Fab")
			(hide yes)
			(effects
				(font
					(size 1 1)
					(thickness 0.15)
				)
				(justify mirror)
			)
		)
		(property "MPN" "GRM155R61H104KE14D"
			(at 95.6 225.36 0)
			(layer "B.Fab")
			(hide yes)
			(effects
				(font
					(size 1 1)
					(thickness 0.15)
				)
				(justify mirror)
			)
		)
		(property "Manufacturer" "Murata"
			(at 95.6 225.36 0)
			(layer "B.Fab")
			(hide yes)
			(effects
				(font
					(size 1 1)
					(thickness 0.15)
				)
				(justify mirror)
			)
		)
		(property "Val" "100n"
			(at 95.6 225.36 0)
			(layer "B.Fab")
			(hide yes)
			(effects
				(font
					(size 1 1)
					(thickness 0.15)
				)
				(justify mirror)
			)
		)
		(property "Voltage" "50V"
			(at 95.6 225.36 0)
			(layer "B.Fab")
			(hide yes)
			(effects
				(font
					(size 1 1)
					(thickness 0.15)
				)
				(justify mirror)
			)
		)
		(sheetname "USB Debug, DP")
		(sheetfile "usb.kicad_sch")
		(attr smd)
		(fp_rect
			(start -0.925 0.47)
			(end 0.925 -0.47)
			(stroke
				(width 0.05)
				(type default)
			)
			(fill none)
			(layer "B.CrtYd")
		)
		(fp_line
			(start 0.504 0.25)
			(end -0.494 0.25)
			(stroke
				(width 0.15)
				(type solid)
			)
			(layer "B.Fab")
		)
		(fp_line
			(start 0.504 -0.248)
			(end 0.504 0.25)
			(stroke
				(width 0.15)
				(type solid)
			)
			(layer "B.Fab")
		)
		(fp_line
			(start -0.494 0.25)
			(end -0.494 -0.248)
			(stroke
				(width 0.15)
				(type solid)
			)
			(layer "B.Fab")
		)
		(fp_line
			(start -0.494 -0.248)
			(end 0.504 -0.248)
			(stroke
				(width 0.15)
				(type solid)
			)
			(layer "B.Fab")
		)
		(fp_text user "Author: Antmicro"
			(at -0.939 -3.399 0)
			(layer "B.Fab")
			(hide yes)
			(effects
				(font
					(size 0.7 0.7)
					(thickness 0.15)
				)
				(justify left bottom mirror)
			)
		)
		(fp_text user "License: Apache-2.0"
			(at -0.939 -5.799 0)
			(layer "B.Fab")
			(hide yes)
			(effects
				(font
					(size 0.7 0.7)
					(thickness 0.15)
				)
				(justify left bottom mirror)
			)
		)
		(fp_text user "${REFERENCE}"
			(at -0.939 -4.599 0)
			(layer "B.Fab")
			(hide yes)
			(effects
				(font
					(size 0.7 0.7)
					(thickness 0.15)
				)
				(justify left bottom mirror)
			)
		)
		(pad "1" smd roundrect
			(at -0.48 0 180)
			(size 0.59 0.64)
			(layers "B.Cu" "B.Paste" "B.Mask")
			(roundrect_rratio 0.25)
			(net 185 "/USB Debug, DP/FTDI_3V3")
			(pintype "passive")
		)
		(pad "2" smd roundrect
			(at 0.48 0 180)
			(size 0.59 0.64)
			(layers "B.Cu" "B.Paste" "B.Mask")
			(roundrect_rratio 0.25)
			(net 1 "GND")
			(pintype "passive")
		)
	)
	(footprint "antmicro-footprints:C_0402_1005Metric"
		(layer "B.Cu")
		(at 35.985 69.5 180)
		(descr "Capacitor SMD 0402")
		(tags "capacitor SMD 0402")
		(property "Reference" "C52"
			(at 0.835 -0.5 0)
			(layer "B.SilkS")
			(effects
				(font
					(size 0.7 0.7)
					(thickness 0.15)
				)
				(justify left bottom mirror)
			)
		)
		(property "Value" "C_100n_0402"
			(at 0 -1.4 0)
			(layer "B.Fab")
			(effects
				(font
					(size 0.7 0.7)
					(thickness 0.15)
				)
				(justify left bottom mirror)
			)
		)
		(property "Footprint" "antmicro-footprints:C_0402_1005Metric"
			(at 0 0 180)
			(layer "F.Fab")
			(hide yes)
			(effects
				(font
					(size 1.27 1.27)
					(thickness 0.15)
				)
			)
		)
		(property "Datasheet" "https://www.murata.com/products/productdetail?partno=GRM155R61H104KE14%23"
			(at 0 0 180)
			(layer "F.Fab")
			(hide yes)
			(effects
				(font
					(size 1.27 1.27)
					(thickness 0.15)
				)
			)
		)
		(property "Author" "Antmicro"
			(at 71.97 139 0)
			(layer "B.Fab")
			(hide yes)
			(effects
				(font
					(size 1 1)
					(thickness 0.15)
				)
				(justify mirror)
			)
		)
		(property "Dielectric" "X5R"
			(at 71.97 139 0)
			(layer "B.Fab")
			(hide yes)
			(effects
				(font
					(size 1 1)
					(thickness 0.15)
				)
				(justify mirror)
			)
		)
		(property "License" "Apache-2.0"
			(at 71.97 139 0)
			(layer "B.Fab")
			(hide yes)
			(effects
				(font
					(size 1 1)
					(thickness 0.15)
				)
				(justify mirror)
			)
		)
		(property "MPN" "GRM155R61H104KE14D"
			(at 71.97 139 0)
			(layer "B.Fab")
			(hide yes)
			(effects
				(font
					(size 1 1)
					(thickness 0.15)
				)
				(justify mirror)
			)
		)
		(property "Manufacturer" "Murata"
			(at 71.97 139 0)
			(layer "B.Fab")
			(hide yes)
			(effects
				(font
					(size 1 1)
					(thickness 0.15)
				)
				(justify mirror)
			)
		)
		(property "Val" "100n"
			(at 71.97 139 0)
			(layer "B.Fab")
			(hide yes)
			(effects
				(font
					(size 1 1)
					(thickness 0.15)
				)
				(justify mirror)
			)
		)
		(property "Voltage" "50V"
			(at 71.97 139 0)
			(layer "B.Fab")
			(hide yes)
			(effects
				(font
					(size 1 1)
					(thickness 0.15)
				)
				(justify mirror)
			)
		)
		(sheetname "Ethernet")
		(sheetfile "ethernet.kicad_sch")
		(attr smd)
		(fp_rect
			(start -0.925 0.47)
			(end 0.925 -0.47)
			(stroke
				(width 0.05)
				(type default)
			)
			(fill none)
			(layer "B.CrtYd")
		)
		(fp_line
			(start 0.504 0.25)
			(end -0.494 0.25)
			(stroke
				(width 0.15)
				(type solid)
			)
			(layer "B.Fab")
		)
		(fp_line
			(start 0.504 -0.248)
			(end 0.504 0.25)
			(stroke
				(width 0.15)
				(type solid)
			)
			(layer "B.Fab")
		)
		(fp_line
			(start -0.494 0.25)
			(end -0.494 -0.248)
			(stroke
				(width 0.15)
				(type solid)
			)
			(layer "B.Fab")
		)
		(fp_line
			(start -0.494 -0.248)
			(end 0.504 -0.248)
			(stroke
				(width 0.15)
				(type solid)
			)
			(layer "B.Fab")
		)
		(fp_text user "${REFERENCE}"
			(at -0.932 -3.168 0)
			(layer "B.Fab")
			(hide yes)
			(effects
				(font
					(size 0.7 0.7)
					(thickness 0.15)
				)
				(justify left bottom mirror)
			)
		)
		(fp_text user "Author: Antmicro"
			(at -0.932 -4.17 0)
			(layer "B.Fab")
			(hide yes)
			(effects
				(font
					(size 0.7 0.7)
					(thickness 0.15)
				)
				(justify left bottom mirror)
			)
		)
		(fp_text user "License: Apache-2.0"
			(at -0.932 -5.17 0)
			(layer "B.Fab")
			(hide yes)
			(effects
				(font
					(size 0.7 0.7)
					(thickness 0.15)
				)
				(justify left bottom mirror)
			)
		)
		(pad "1" smd roundrect
			(at -0.48 0 180)
			(size 0.59 0.64)
			(layers "B.Cu" "B.Paste" "B.Mask")
			(roundrect_rratio 0.25)
			(net 500 "POE_OUTPUT")
			(pintype "passive")
		)
		(pad "2" smd roundrect
			(at 0.48 0 180)
			(size 0.59 0.64)
			(layers "B.Cu" "B.Paste" "B.Mask")
			(roundrect_rratio 0.25)
			(net 1 "GND")
			(pintype "passive")
		)
	)
	(footprint "antmicro-footprints:LED_0603_1608Metric_G"
		(layer "B.Cu")
		(at 77.25 105.45 90)
		(descr "LED SMD 0603 Green")
		(tags "LED SMD 0603 Green")
		(property "Reference" "D5"
			(at 1.2 -0.8 180)
			(layer "B.SilkS")
			(effects
				(font
					(size 0.7 0.7)
					(thickness 0.15)
				)
				(justify right bottom mirror)
			)
		)
		(property "Value" "LED_G_0603_LTST-C190GKT"
			(at -0.001 -1.599 90)
			(layer "B.Fab")
			(effects
				(font
					(size 0.7 0.7)
					(thickness 0.15)
				)
				(justify right bottom mirror)
			)
		)
		(property "Footprint" "antmicro-footprints:LED_0603_1608Metric_G"
			(at 0 0 90)
			(layer "F.Fab")
			(hide yes)
			(effects
				(font
					(size 1.27 1.27)
					(thickness 0.15)
				)
			)
		)
		(property "Datasheet" "https://media.digikey.com/pdf/Data%20Sheets/Lite-On%20PDFs/LTST-C190GKT.pdf"
			(at 0 0 90)
			(layer "F.Fab")
			(hide yes)
			(effects
				(font
					(size 1.27 1.27)
					(thickness 0.15)
				)
			)
		)
		(property "Author" "Antmicro"
			(at 182.7 28.2 0)
			(layer "B.Fab")
			(hide yes)
			(effects
				(font
					(size 1 1)
					(thickness 0.15)
				)
				(justify mirror)
			)
		)
		(property "Color" "Green"
			(at 182.7 28.2 0)
			(layer "B.Fab")
			(hide yes)
			(effects
				(font
					(size 1 1)
					(thickness 0.15)
				)
				(justify mirror)
			)
		)
		(property "License" "Apache-2.0"
			(at 182.7 28.2 0)
			(layer "B.Fab")
			(hide yes)
			(effects
				(font
					(size 1 1)
					(thickness 0.15)
				)
				(justify mirror)
			)
		)
		(property "MPN" "LTST-C190GKT"
			(at 182.7 28.2 0)
			(layer "B.Fab")
			(hide yes)
			(effects
				(font
					(size 1 1)
					(thickness 0.15)
				)
				(justify mirror)
			)
		)
		(property "Manufacturer" "Lite-On"
			(at 182.7 28.2 0)
			(layer "B.Fab")
			(hide yes)
			(effects
				(font
					(size 1 1)
					(thickness 0.15)
				)
				(justify mirror)
			)
		)
		(sheetname "USB Debug, DP")
		(sheetfile "usb.kicad_sch")
		(attr smd)
		(fp_line
			(start -0.22 -0.35)
			(end 0.22 -0.35)
			(stroke
				(width 0.15)
				(type solid)
			)
			(layer "B.SilkS")
		)
		(fp_line
			(start -1.18 -0.321)
			(end -1.18 0.319)
			(stroke
				(width 0.15)
				(type solid)
			)
			(layer "B.SilkS")
		)
		(fp_line
			(start -0.094672 -0.001008)
			(end 0.105328 -0.201008)
			(stroke
				(width 0.1)
				(type solid)
			)
			(layer "B.SilkS")
		)
		(fp_line
			(start -0.24 -0.001008)
			(end -0.094672 -0.001008)
			(stroke
				(width 0.1)
				(type solid)
			)
			(layer "B.SilkS")
		)
		(fp_line
			(start 0.24 -0.001)
			(end 0.105328 -0.001008)
			(stroke
				(width 0.1)
				(type solid)
			)
			(layer "B.SilkS")
		)
		(fp_line
			(start 0.105328 0.198992)
			(end 0.105328 -0.201008)
			(stroke
				(width 0.1)
				(type solid)
			)
			(layer "B.SilkS")
		)
		(fp_line
			(start 0.105328 0.198992)
			(end -0.094672 -0.001008)
			(stroke
				(width 0.1)
				(type solid)
			)
			(layer "B.SilkS")
		)
		(fp_line
			(start -0.094672 0.198992)
			(end -0.094672 -0.201008)
			(stroke
				(width 0.1)
				(type solid)
			)
			(layer "B.SilkS")
		)
		(fp_line
			(start -0.22 0.35)
			(end 0.22 0.35)
			(stroke
				(width 0.15)
				(type solid)
			)
			(layer "B.SilkS")
		)
		(fp_rect
			(start 1.25 -0.65)
			(end -1.25 0.65)
			(stroke
				(width 0.05)
				(type solid)
			)
			(fill none)
			(layer "B.CrtYd")
		)
		(fp_line
			(start 0.201 -0.2)
			(end -0.101 0)
			(stroke
				(width 0.15)
				(type solid)
			)
			(layer "B.Fab")
		)
		(fp_line
			(start -0.199 -0.1)
			(end -0.199 -0.2)
			(stroke
				(width 0.15)
				(type solid)
			)
			(layer "B.Fab")
		)
		(fp_line
			(start -0.199 -0.1)
			(end -0.199 0.202)
			(stroke
				(width 0.15)
				(type solid)
			)
			(layer "B.Fab")
		)
		(fp_line
			(start 0.201 0)
			(end 0.201 -0.2)
			(stroke
				(width 0.15)
				(type solid)
			)
			(layer "B.Fab")
		)
		(fp_line
			(start 0.201 0)
			(end 0.599 0)
			(stroke
				(width 0.15)
				(type solid)
			)
			(layer "B.Fab")
		)
		(fp_line
			(start -0.101 0)
			(end 0.201 0.202)
			(stroke
				(width 0.15)
				(type solid)
			)
			(layer "B.Fab")
		)
		(fp_line
			(start -0.597 0)
			(end -0.199 0)
			(stroke
				(width 0.15)
				(type solid)
			)
			(layer "B.Fab")
		)
		(fp_line
			(start 0.201 0.202)
			(end 0.201 0)
			(stroke
				(width 0.15)
				(type solid)
			)
			(layer "B.Fab")
		)
		(fp_rect
			(start 0.848 -0.4)
			(end -0.85 0.402)
			(stroke
				(width 0.15)
				(type solid)
			)
			(fill none)
			(layer "B.Fab")
		)
		(fp_text user "${REFERENCE}"
			(at -1.4224 -5.999 90)
			(layer "B.Fab")
			(hide yes)
			(effects
				(font
					(size 0.7 0.7)
					(thickness 0.15)
				)
				(justify right bottom mirror)
			)
		)
		(fp_text user "Author: Antmicro"
			(at -1.4224 -4.799 90)
			(layer "B.Fab")
			(hide yes)
			(effects
				(font
					(size 0.7 0.7)
					(thickness 0.15)
				)
				(justify right bottom mirror)
			)
		)
		(fp_text user "License: Apache-2.0"
			(at -1.4224 -3.599 90)
			(layer "B.Fab")
			(hide yes)
			(effects
				(font
					(size 0.7 0.7)
					(thickness 0.15)
				)
				(justify right bottom mirror)
			)
		)
		(pad "1" smd roundrect
			(at -0.7 0 270)
			(size 0.8 1)
			(layers "B.Cu" "B.Paste" "B.Mask")
			(roundrect_rratio 0.2)
			(net 1 "GND")
			(pinfunction "C")
			(pintype "passive")
		)
		(pad "2" smd roundrect
			(at 0.7 0 270)
			(size 0.8 1)
			(layers "B.Cu" "B.Paste" "B.Mask")
			(roundrect_rratio 0.2)
			(net 145 "Net-(D5-A)")
			(pinfunction "A")
			(pintype "passive")
		)
	)
)
